G04*
G04 #@! TF.GenerationSoftware,Altium Limited,Altium Designer,23.0.1 (38)*
G04*
G04 Layer_Color=16711935*
%FSLAX44Y44*%
%MOMM*%
G71*
G04*
G04 #@! TF.SameCoordinates,9A23C038-B079-480F-8166-AFFB5740F5AE*
G04*
G04*
G04 #@! TF.FilePolarity,Negative*
G04*
G01*
G75*
%ADD41C,0.6500*%
G36*
X56531Y68583D02*
X57536Y68430D01*
X58526Y68201D01*
X59495Y67899D01*
X60440Y67523D01*
X61353Y67078D01*
X62229Y66564D01*
X63065Y65986D01*
X63854Y65347D01*
X64593Y64649D01*
X65277Y63898D01*
X65903Y63097D01*
X66465Y62251D01*
X66963Y61365D01*
X67392Y60444D01*
X67750Y59493D01*
X68035Y58518D01*
X68246Y57524D01*
X68285Y57228D01*
X68410Y56010D01*
X68410Y56010D01*
X68410Y56010D01*
Y4973D01*
X67512Y4075D01*
X10450Y4078D01*
X10450Y4078D01*
X10450Y4078D01*
X9822D01*
X8591Y4323D01*
X7432Y4803D01*
X6388Y5501D01*
X5501Y6388D01*
X4803Y7432D01*
X4323Y8591D01*
X4078Y9822D01*
X4078Y10450D01*
X4078Y10450D01*
X4078Y10450D01*
X4074Y67762D01*
X4972Y68660D01*
X55010Y68660D01*
X55518Y68660D01*
X56531Y68583D01*
D02*
G37*
G36*
X68366Y312495D02*
X68366Y269837D01*
X68146Y267691D01*
X66929Y263550D01*
X64977Y259702D01*
X62356Y256274D01*
X59152Y253382D01*
X55475Y251124D01*
X51447Y249575D01*
X47204Y248787D01*
X45046Y248787D01*
X4062D01*
X4058Y306760D01*
X4058Y307413D01*
X4313Y308693D01*
X4812Y309900D01*
X5537Y310985D01*
X6460Y311909D01*
X7545Y312635D01*
X8751Y313135D01*
X10031Y313391D01*
X10684Y313392D01*
X67468Y313393D01*
X68366Y312495D01*
D02*
G37*
G36*
X667638Y67762D02*
X667632Y10150D01*
X667632Y10150D01*
X667632Y10150D01*
X667632Y9548D01*
X667397Y8368D01*
X666937Y7257D01*
X666269Y6256D01*
X665419Y5405D01*
X664419Y4736D01*
X663307Y4275D01*
X662128Y4039D01*
X661526Y4038D01*
X593410Y4042D01*
Y10043D01*
X593410Y51910D01*
X593498Y53590D01*
X594305Y56857D01*
X595713Y59913D01*
X597673Y62648D01*
X600114Y64964D01*
X602948Y66778D01*
X606073Y68025D01*
X609378Y68660D01*
X611060D01*
X611060Y68660D01*
X666740D01*
X667638Y67762D01*
D02*
G37*
G36*
X662899Y313154D02*
X664122Y312648D01*
X665223Y311913D01*
X666159Y310977D01*
X666895Y309878D01*
X667402Y308655D01*
X667661Y307358D01*
X667662Y306697D01*
X667656Y248760D01*
X612290Y248760D01*
X610481D01*
X606929Y249446D01*
X603571Y250794D01*
X600530Y252755D01*
X597916Y255256D01*
X595824Y258208D01*
X594331Y261504D01*
X593489Y265023D01*
X593410Y266830D01*
Y270209D01*
X593410Y313410D01*
X660940Y313412D01*
X661602D01*
X662899Y313154D01*
D02*
G37*
%LPC*%
G36*
X30037Y48469D02*
X26983D01*
X26852Y48460D01*
X26721D01*
X26591Y48443D01*
X26460Y48434D01*
X26331Y48409D01*
X26201Y48391D01*
X23207Y47796D01*
X23080Y47762D01*
X22951Y47736D01*
X22827Y47694D01*
X22700Y47660D01*
X22579Y47610D01*
X22455Y47568D01*
X19634Y46399D01*
X19517Y46341D01*
X19395Y46291D01*
X19281Y46225D01*
X19164Y46167D01*
X19055Y46095D01*
X18941Y46029D01*
X16402Y44333D01*
X16298Y44253D01*
X16189Y44180D01*
X16091Y44093D01*
X15986Y44014D01*
X15893Y43921D01*
X15795Y43834D01*
X13636Y41675D01*
X13549Y41577D01*
X13456Y41484D01*
X13377Y41379D01*
X13290Y41281D01*
X13217Y41172D01*
X13137Y41068D01*
X11441Y38529D01*
X11375Y38415D01*
X11302Y38306D01*
X11244Y38189D01*
X11179Y38075D01*
X11129Y37954D01*
X11071Y37836D01*
X9902Y35015D01*
X9860Y34891D01*
X9810Y34770D01*
X9776Y34643D01*
X9734Y34519D01*
X9708Y34390D01*
X9674Y34263D01*
X9078Y31269D01*
X9061Y31138D01*
X9036Y31010D01*
X9027Y30879D01*
X9010Y30749D01*
Y30618D01*
X9001Y30487D01*
Y27433D01*
X9010Y27302D01*
Y27171D01*
X9027Y27041D01*
X9036Y26910D01*
X9061Y26782D01*
X9078Y26651D01*
X9674Y23657D01*
X9708Y23530D01*
X9734Y23401D01*
X9776Y23277D01*
X9810Y23150D01*
X9860Y23029D01*
X9902Y22905D01*
X11071Y20084D01*
X11129Y19966D01*
X11179Y19845D01*
X11245Y19731D01*
X11302Y19614D01*
X11375Y19505D01*
X11441Y19391D01*
X13137Y16852D01*
X13217Y16748D01*
X13290Y16639D01*
X13377Y16540D01*
X13456Y16436D01*
X13549Y16343D01*
X13636Y16245D01*
X15795Y14086D01*
X15893Y13999D01*
X15986Y13907D01*
X16091Y13827D01*
X16189Y13740D01*
X16298Y13667D01*
X16402Y13587D01*
X18941Y11891D01*
X19055Y11825D01*
X19164Y11753D01*
X19281Y11695D01*
X19395Y11629D01*
X19516Y11579D01*
X19634Y11521D01*
X22455Y10352D01*
X22579Y10310D01*
X22700Y10260D01*
X22827Y10226D01*
X22951Y10184D01*
X23080Y10158D01*
X23207Y10124D01*
X26201Y9528D01*
X26332Y9511D01*
X26460Y9486D01*
X26591Y9477D01*
X26721Y9460D01*
X26852D01*
X26983Y9451D01*
X30037D01*
X30168Y9460D01*
X30299D01*
X30429Y9477D01*
X30560Y9486D01*
X30688Y9511D01*
X30819Y9528D01*
X33813Y10124D01*
X33940Y10158D01*
X34069Y10184D01*
X34193Y10226D01*
X34320Y10260D01*
X34441Y10310D01*
X34565Y10352D01*
X37386Y11521D01*
X37503Y11579D01*
X37625Y11629D01*
X37739Y11695D01*
X37856Y11753D01*
X37965Y11825D01*
X38079Y11891D01*
X40618Y13587D01*
X40722Y13667D01*
X40831Y13740D01*
X40929Y13827D01*
X41034Y13907D01*
X41127Y13999D01*
X41225Y14086D01*
X43384Y16245D01*
X43471Y16343D01*
X43563Y16436D01*
X43643Y16540D01*
X43730Y16639D01*
X43803Y16748D01*
X43883Y16852D01*
X45579Y19391D01*
X45645Y19505D01*
X45718Y19614D01*
X45775Y19732D01*
X45841Y19845D01*
X45891Y19966D01*
X45949Y20084D01*
X47118Y22905D01*
X47160Y23029D01*
X47210Y23150D01*
X47244Y23277D01*
X47286Y23401D01*
X47312Y23530D01*
X47346Y23657D01*
X47941Y26651D01*
X47959Y26781D01*
X47984Y26910D01*
X47993Y27041D01*
X48010Y27171D01*
Y27302D01*
X48019Y27433D01*
Y30487D01*
X48010Y30618D01*
Y30749D01*
X47993Y30879D01*
X47984Y31010D01*
X47959Y31139D01*
X47941Y31269D01*
X47346Y34263D01*
X47312Y34390D01*
X47286Y34519D01*
X47244Y34643D01*
X47210Y34770D01*
X47160Y34891D01*
X47118Y35015D01*
X45949Y37836D01*
X45891Y37954D01*
X45841Y38075D01*
X45775Y38189D01*
X45718Y38306D01*
X45645Y38415D01*
X45579Y38529D01*
X43883Y41068D01*
X43803Y41172D01*
X43730Y41281D01*
X43643Y41379D01*
X43563Y41484D01*
X43471Y41577D01*
X43384Y41675D01*
X41225Y43834D01*
X41127Y43921D01*
X41034Y44014D01*
X40929Y44093D01*
X40831Y44180D01*
X40722Y44253D01*
X40618Y44333D01*
X38079Y46029D01*
X37965Y46095D01*
X37856Y46167D01*
X37738Y46226D01*
X37625Y46291D01*
X37504Y46341D01*
X37386Y46399D01*
X34565Y47568D01*
X34441Y47610D01*
X34320Y47660D01*
X34193Y47694D01*
X34069Y47736D01*
X33940Y47762D01*
X33813Y47796D01*
X30819Y48391D01*
X30689Y48409D01*
X30560Y48434D01*
X30429Y48443D01*
X30299Y48460D01*
X30168D01*
X30037Y48469D01*
D02*
G37*
G36*
Y308538D02*
X26983D01*
X26589Y308460D01*
X26188D01*
X23193Y307864D01*
X22822Y307711D01*
X22428Y307632D01*
X19607Y306464D01*
X19273Y306241D01*
X18902Y306087D01*
X16364Y304391D01*
X16079Y304107D01*
X15746Y303883D01*
X13586Y301724D01*
X13363Y301390D01*
X13079Y301106D01*
X11383Y298568D01*
X11229Y298197D01*
X11006Y297863D01*
X9838Y295042D01*
X9759Y294648D01*
X9606Y294277D01*
X9010Y291282D01*
Y290881D01*
X8932Y290487D01*
Y287433D01*
X9010Y287039D01*
Y286638D01*
X9606Y283643D01*
X9759Y283272D01*
X9838Y282878D01*
X11006Y280057D01*
X11229Y279723D01*
X11383Y279352D01*
X13079Y276814D01*
X13363Y276529D01*
X13586Y276196D01*
X15746Y274037D01*
X16079Y273813D01*
X16364Y273529D01*
X18902Y271833D01*
X19273Y271679D01*
X19607Y271456D01*
X22428Y270288D01*
X22822Y270209D01*
X23193Y270056D01*
X26188Y269460D01*
X26589D01*
X26983Y269382D01*
X30037D01*
X30431Y269460D01*
X30832D01*
X33827Y270056D01*
X34198Y270209D01*
X34592Y270288D01*
X37413Y271456D01*
X37747Y271679D01*
X38118Y271833D01*
X40656Y273529D01*
X40941Y273813D01*
X41274Y274037D01*
X43433Y276196D01*
X43657Y276530D01*
X43941Y276814D01*
X45637Y279352D01*
X45791Y279723D01*
X46014Y280057D01*
X47182Y282878D01*
X47261Y283272D01*
X47414Y283643D01*
X48010Y286638D01*
Y287039D01*
X48088Y287433D01*
Y290487D01*
X48010Y290881D01*
Y291282D01*
X47414Y294277D01*
X47261Y294648D01*
X47182Y295042D01*
X46014Y297863D01*
X45791Y298197D01*
X45637Y298568D01*
X43941Y301106D01*
X43657Y301391D01*
X43433Y301724D01*
X41274Y303883D01*
X40940Y304107D01*
X40656Y304391D01*
X38118Y306087D01*
X37747Y306241D01*
X37413Y306464D01*
X34592Y307632D01*
X34198Y307711D01*
X33827Y307864D01*
X30832Y308460D01*
X30431D01*
X30037Y308538D01*
D02*
G37*
G36*
X635037Y48538D02*
X631983D01*
X631589Y48460D01*
X631188D01*
X628193Y47864D01*
X627822Y47711D01*
X627428Y47632D01*
X624607Y46464D01*
X624273Y46241D01*
X623902Y46087D01*
X621363Y44391D01*
X621079Y44107D01*
X620746Y43884D01*
X618587Y41725D01*
X618363Y41391D01*
X618079Y41107D01*
X616383Y38568D01*
X616229Y38197D01*
X616006Y37863D01*
X614838Y35042D01*
X614759Y34648D01*
X614606Y34277D01*
X614010Y31282D01*
Y30881D01*
X613932Y30487D01*
Y27433D01*
X614010Y27039D01*
Y26638D01*
X614606Y23643D01*
X614759Y23272D01*
X614838Y22878D01*
X616006Y20057D01*
X616229Y19723D01*
X616383Y19352D01*
X618079Y16813D01*
X618363Y16529D01*
X618587Y16195D01*
X620746Y14037D01*
X621079Y13813D01*
X621363Y13529D01*
X623902Y11833D01*
X624273Y11679D01*
X624607Y11456D01*
X627428Y10288D01*
X627822Y10209D01*
X628193Y10056D01*
X631188Y9460D01*
X631589D01*
X631983Y9382D01*
X635037D01*
X635431Y9460D01*
X635832D01*
X638827Y10056D01*
X639198Y10209D01*
X639592Y10288D01*
X642413Y11456D01*
X642747Y11679D01*
X643118Y11833D01*
X645657Y13529D01*
X645941Y13813D01*
X646274Y14037D01*
X648434Y16195D01*
X648657Y16530D01*
X648941Y16813D01*
X650637Y19352D01*
X650791Y19723D01*
X651014Y20057D01*
X652182Y22878D01*
X652261Y23272D01*
X652414Y23643D01*
X653010Y26638D01*
Y27039D01*
X653088Y27433D01*
Y30487D01*
X653010Y30881D01*
Y31282D01*
X652414Y34277D01*
X652261Y34648D01*
X652182Y35042D01*
X651014Y37863D01*
X650791Y38197D01*
X650637Y38568D01*
X648941Y41107D01*
X648657Y41391D01*
X648434Y41725D01*
X646274Y43884D01*
X645940Y44107D01*
X645657Y44391D01*
X643118Y46087D01*
X642747Y46241D01*
X642413Y46464D01*
X639592Y47632D01*
X639198Y47711D01*
X638827Y47864D01*
X635832Y48460D01*
X635431D01*
X635037Y48538D01*
D02*
G37*
G36*
Y308538D02*
X631983D01*
X631589Y308460D01*
X631188D01*
X628193Y307864D01*
X627822Y307711D01*
X627428Y307632D01*
X624607Y306464D01*
X624273Y306241D01*
X623902Y306087D01*
X621363Y304391D01*
X621079Y304107D01*
X620746Y303883D01*
X618587Y301724D01*
X618363Y301390D01*
X618079Y301106D01*
X616383Y298568D01*
X616229Y298197D01*
X616006Y297863D01*
X614838Y295042D01*
X614759Y294648D01*
X614606Y294277D01*
X614010Y291282D01*
Y290881D01*
X613932Y290487D01*
Y288960D01*
Y287433D01*
X614010Y287039D01*
Y286638D01*
X614606Y283643D01*
X614759Y283272D01*
X614838Y282878D01*
X616006Y280057D01*
X616229Y279723D01*
X616383Y279352D01*
X618079Y276814D01*
X618363Y276529D01*
X618587Y276196D01*
X620746Y274037D01*
X621079Y273813D01*
X621363Y273529D01*
X623902Y271833D01*
X624273Y271679D01*
X624607Y271456D01*
X627428Y270288D01*
X627822Y270209D01*
X628193Y270056D01*
X631188Y269460D01*
X631589D01*
X631983Y269382D01*
X635037D01*
X635431Y269460D01*
X635832D01*
X638827Y270056D01*
X639198Y270209D01*
X639592Y270288D01*
X642413Y271456D01*
X642747Y271679D01*
X643118Y271833D01*
X645657Y273529D01*
X645941Y273813D01*
X646274Y274037D01*
X648434Y276196D01*
X648657Y276530D01*
X648941Y276814D01*
X650637Y279352D01*
X650791Y279723D01*
X651014Y280057D01*
X652182Y282878D01*
X652261Y283272D01*
X652414Y283643D01*
X653010Y286638D01*
Y287039D01*
X653088Y287433D01*
Y288960D01*
Y290487D01*
X653010Y290881D01*
Y291282D01*
X652414Y294277D01*
X652261Y294648D01*
X652182Y295042D01*
X651014Y297863D01*
X650791Y298197D01*
X650637Y298568D01*
X648941Y301106D01*
X648657Y301391D01*
X648434Y301724D01*
X646274Y303883D01*
X645940Y304107D01*
X645657Y304391D01*
X643118Y306087D01*
X642747Y306241D01*
X642413Y306464D01*
X639592Y307632D01*
X639198Y307711D01*
X638827Y307864D01*
X635832Y308460D01*
X635431D01*
X635037Y308538D01*
D02*
G37*
%LPD*%
D41*
X523000Y208039D02*
D03*
X522965Y242000D02*
D03*
X536000Y232691D02*
D03*
Y208000D02*
D03*
X561000Y103000D02*
D03*
Y123000D02*
D03*
X560000Y143000D02*
D03*
M02*
